(kicad_pcb
	(version 20260206)
	(generator "pcbnew")
	(generator_version "10.0")
	(general
		(thickness 1.6)
		(legacy_teardrops no)
	)
	(paper "A4")
	(title_block
		(title "04192023_DAF0TMB3IC0_F0TG_MB_C_brd_V02_OCP.brd")
		(comment 1 "Grand Teton / footprints 4678-4683 of 8354")
	)
	(layers
		(0 "F.Cu" signal "TOP")
		(4 "In1.Cu" signal "GND")
		(6 "In2.Cu" signal "IN1")
		(8 "In3.Cu" signal "GND1")
		(10 "In4.Cu" signal "IN2")
		(12 "In5.Cu" signal "GND2")
		(14 "In6.Cu" signal "IN3")
		(16 "In7.Cu" signal "GND3")
		(18 "In8.Cu" signal "VCC")
		(20 "In9.Cu" signal "VCC1")
		(22 "In10.Cu" signal "GND4")
		(24 "In11.Cu" signal "IN4")
		(26 "In12.Cu" signal "GND5")
		(28 "In13.Cu" signal "IN5")
		(30 "In14.Cu" signal "GND6")
		(32 "In15.Cu" signal "IN6")
		(34 "In16.Cu" signal "GND7")
		(2 "B.Cu" signal "BOTTOM")
		(9 "F.Adhes" user "F.Adhesive")
		(11 "B.Adhes" user "B.Adhesive")
		(13 "F.Paste" user "Package Geometry/Pastemask Top")
		(15 "B.Paste" user "Package Geometry/Pastemask Bottom")
		(5 "F.SilkS" user "Ref Des/Silkscreen Top")
		(7 "B.SilkS" user "Ref Des/Silkscreen Bottom")
		(1 "F.Mask" user "Board Geometry/Soldermask Top")
		(3 "B.Mask" user "Board Geometry/Soldermask Bottom")
		(17 "Dwgs.User" user "User.Drawings")
		(19 "Cmts.User" user "User.Comments")
		(21 "Eco1.User" user "User.Eco1")
		(23 "Eco2.User" user "User.Eco2")
		(25 "Edge.Cuts" user "Board Geometry/Outline")
		(27 "Margin" user)
		(31 "F.CrtYd" user "Package Geometry/Place Bound Top")
		(29 "B.CrtYd" user "Package Geometry/Place Bound Bottom")
		(35 "F.Fab" user "Ref Des/Assembly Top")
		(33 "B.Fab" user "Ref Des/Assembly Bottom")
	)
	(footprint ""
		(layer "F.Cu")
		(at 215.259666 -54.455314)
		(property "Reference" "U276"
			(at 4.349242 0.209042 0)
			(unlocked yes)
			(layer "F.SilkS")
			(effects
				(font
					(size 0.7874 0.5842)
					(thickness 0.1524)
				)
			)
		)
		(property "Value" ""
			(at 0 0 0)
			(layer "F.Fab")
			(effects
				(font
					(size 1.27 1.27)
				)
			)
		)
		(duplicate_pad_numbers_are_jumpers no)
		(fp_line
			(start -1.500124 -1.500124)
			(end -1.004062 -1.500124)
			(stroke
				(width 0.1524)
				(type default)
			)
			(layer "F.SilkS")
		)
		(fp_line
			(start -1.500124 -1.004062)
			(end -1.500124 -1.500124)
			(stroke
				(width 0.1524)
				(type default)
			)
			(layer "F.SilkS")
		)
		(fp_line
			(start -1.500124 1.500124)
			(end -1.500124 1.004062)
			(stroke
				(width 0.1524)
				(type default)
			)
			(layer "F.SilkS")
		)
		(fp_line
			(start -1.004062 1.500124)
			(end -1.500124 1.500124)
			(stroke
				(width 0.1524)
				(type default)
			)
			(layer "F.SilkS")
		)
		(fp_line
			(start 1.004062 -1.500124)
			(end 1.500124 -1.500124)
			(stroke
				(width 0.1524)
				(type default)
			)
			(layer "F.SilkS")
		)
		(fp_line
			(start 1.500124 -1.500124)
			(end 1.500124 -1.004062)
			(stroke
				(width 0.1524)
				(type default)
			)
			(layer "F.SilkS")
		)
		(fp_line
			(start 1.500124 1.004062)
			(end 1.500124 1.500124)
			(stroke
				(width 0.1524)
				(type default)
			)
			(layer "F.SilkS")
		)
		(fp_line
			(start 1.500124 1.500124)
			(end 1.004062 1.500124)
			(stroke
				(width 0.1524)
				(type default)
			)
			(layer "F.SilkS")
		)
		(fp_poly
			(pts
				(xy -2.515616 -1.309878) (xy -2.07137 -1.831086) (xy -1.772158 -1.126236)
			)
			(stroke
				(width 0)
				(type default)
			)
			(fill yes)
			(layer "F.SilkS")
		)
		(fp_line
			(start -1.500124 -1.500124)
			(end 1.500124 -1.500124)
			(stroke
				(width 0.1)
				(type default)
			)
			(layer "F.Fab")
		)
		(fp_line
			(start -1.500124 1.500124)
			(end -1.500124 -1.500124)
			(stroke
				(width 0.1)
				(type default)
			)
			(layer "F.Fab")
		)
		(fp_line
			(start 1.500124 -1.500124)
			(end 1.500124 1.500124)
			(stroke
				(width 0.1)
				(type default)
			)
			(layer "F.Fab")
		)
		(fp_line
			(start 1.500124 1.500124)
			(end -1.500124 1.500124)
			(stroke
				(width 0.1)
				(type default)
			)
			(layer "F.Fab")
		)
		(fp_poly
			(pts
				(xy -2.847848 -1.258062) (xy -2.847848 -0.242062) (xy -1.831848 -0.750062)
			)
			(stroke
				(width 0)
				(type default)
			)
			(fill yes)
			(layer "F.Fab")
		)
		(pad "1" smd rect
			(at -1.400048 -0.750062 270)
			(size 0.2286 0.6096)
			(layers "F.Cu" "F.Mask" "F.Paste")
			(net "INA230_2_A1")
		)
		(pad "2" smd rect
			(at -1.400048 -0.249936 270)
			(size 0.2286 0.6096)
			(layers "F.Cu" "F.Mask" "F.Paste")
			(net "INA230_2_A0")
		)
		(pad "3" smd rect
			(at -1.400048 0.249936 270)
			(size 0.2286 0.6096)
			(layers "F.Cu" "F.Mask" "F.Paste")
			(net "E1S_0_P3V3_ADC_ALERT_R")
		)
		(pad "4" smd rect
			(at -1.400048 0.750062 270)
			(size 0.2286 0.6096)
			(layers "F.Cu" "F.Mask" "F.Paste")
			(net "SMB_INA230_2_3V3AUX_SDA_R1")
		)
		(pad "5" smd rect
			(at -0.750062 1.400048)
			(size 0.2286 0.6096)
			(layers "F.Cu" "F.Mask" "F.Paste")
			(net "SMB_INA230_2_3V3AUX_SCL_R1")
		)
		(pad "6" smd rect
			(at -0.249936 1.400048)
			(size 0.2286 0.6096)
			(layers "F.Cu" "F.Mask" "F.Paste")
			(net "NC_INA230_2_NC0")
		)
		(pad "7" smd rect
			(at 0.249936 1.400048)
			(size 0.2286 0.6096)
			(layers "F.Cu" "F.Mask" "F.Paste")
			(net "NC_INA230_2_NC1")
		)
		(pad "8" smd rect
			(at 0.750062 1.400048)
			(size 0.2286 0.6096)
			(layers "F.Cu" "F.Mask" "F.Paste")
			(net "NC_INA230_2_NC2")
		)
		(pad "9" smd rect
			(at 1.400048 0.750062 270)
			(size 0.2286 0.6096)
			(layers "F.Cu" "F.Mask" "F.Paste")
			(net "P3V3_AUX")
		)
		(pad "10" smd rect
			(at 1.400048 0.249936 270)
			(size 0.2286 0.6096)
			(layers "F.Cu" "F.Mask" "F.Paste")
			(net "GND")
		)
		(pad "11" smd rect
			(at 1.400048 -0.249936 270)
			(size 0.2286 0.6096)
			(layers "F.Cu" "F.Mask" "F.Paste")
			(net "P3V3_E1S_0_R")
		)
		(pad "12" smd rect
			(at 1.400048 -0.750062 270)
			(size 0.2286 0.6096)
			(layers "F.Cu" "F.Mask" "F.Paste")
			(net "VSENSE_P3V3_INA230_2_INN")
		)
		(pad "13" smd rect
			(at 0.750062 -1.400048)
			(size 0.2286 0.6096)
			(layers "F.Cu" "F.Mask" "F.Paste")
			(net "VSENSE_P3V3_INA230_2_INP")
		)
		(pad "14" smd rect
			(at 0.249936 -1.400048)
			(size 0.2286 0.6096)
			(layers "F.Cu" "F.Mask" "F.Paste")
			(net "NC_INA230_2_NC3")
		)
		(pad "15" smd rect
			(at -0.249936 -1.400048)
			(size 0.2286 0.6096)
			(layers "F.Cu" "F.Mask" "F.Paste")
			(net "NC_INA230_2_NC4")
		)
		(pad "16" smd rect
			(at -0.750062 -1.400048)
			(size 0.2286 0.6096)
			(layers "F.Cu" "F.Mask" "F.Paste")
			(net "NC_INA230_2_NC5")
		)
		(pad "TH" smd rect
			(at 0 0)
			(size 1.7018 1.7018)
			(layers "F.Cu" "F.Mask" "F.Paste")
			(net "GND")
		)
		(zone
			(layer "F.Cu")
			(hatch none 0.5)
			(connect_pads
				(clearance 0)
			)
			(min_thickness 0.25)
			(keepout
				(tracks not_allowed)
				(vias allowed)
				(pads allowed)
				(copperpour not_allowed)
				(footprints allowed)
			)
			(placement
				(enabled no)
				(sheetname "")
			)
			(fill
				(thermal_gap 0.5)
				(thermal_bridge_width 0.5)
				(island_removal_mode 0)
			)
			(polygon
				(pts
					(xy 214.215218 -54.455314) (xy 214.357966 -54.455314) (xy 214.357966 -53.553614) (xy 216.161366 -53.553614)
					(xy 216.161366 -53.967888) (xy 216.304114 -53.967888) (xy 216.304114 -53.410866) (xy 214.215218 -53.410866)
				)
			)
		)
	)
	(footprint ""
		(layer "F.Cu")
		(at 122.427238 -41.17975 -90)
		(property "Reference" "R6259"
			(at 0 0 270)
			(layer "F.SilkS")
			(hide yes)
			(effects
				(font
					(size 1.27 1.27)
				)
			)
		)
		(property "Value" ""
			(at 0 0 270)
			(layer "F.Fab")
			(effects
				(font
					(size 1.27 1.27)
				)
			)
		)
		(duplicate_pad_numbers_are_jumpers no)
		(fp_line
			(start -0.7874 0.4064)
			(end -0.7874 -0.4064)
			(stroke
				(width 0.1524)
				(type default)
			)
			(layer "F.SilkS")
		)
		(fp_line
			(start 0.7874 0.4064)
			(end -0.7874 0.4064)
			(stroke
				(width 0.1524)
				(type default)
			)
			(layer "F.SilkS")
		)
		(fp_line
			(start -0.7874 -0.4064)
			(end 0.7874 -0.4064)
			(stroke
				(width 0.1524)
				(type default)
			)
			(layer "F.SilkS")
		)
		(fp_line
			(start 0.7874 -0.4064)
			(end 0.7874 0.4064)
			(stroke
				(width 0.1524)
				(type default)
			)
			(layer "F.SilkS")
		)
		(fp_line
			(start -0.67945 0.3048)
			(end -0.67945 -0.305054)
			(stroke
				(width 0.1)
				(type default)
			)
			(layer "F.Fab")
		)
		(fp_line
			(start -0.12065 0.3048)
			(end -0.67945 0.3048)
			(stroke
				(width 0.1)
				(type default)
			)
			(layer "F.Fab")
		)
		(fp_line
			(start 0.120396 0.3048)
			(end 0.120396 0.2794)
			(stroke
				(width 0.1)
				(type default)
			)
			(layer "F.Fab")
		)
		(fp_line
			(start 0.67945 0.3048)
			(end 0.120396 0.3048)
			(stroke
				(width 0.1)
				(type default)
			)
			(layer "F.Fab")
		)
		(fp_line
			(start -0.12065 0.2794)
			(end -0.12065 0.3048)
			(stroke
				(width 0.1)
				(type default)
			)
			(layer "F.Fab")
		)
		(fp_line
			(start 0.120396 0.2794)
			(end -0.12065 0.2794)
			(stroke
				(width 0.1)
				(type default)
			)
			(layer "F.Fab")
		)
		(fp_line
			(start -0.12065 -0.2794)
			(end 0.12065 -0.2794)
			(stroke
				(width 0.1)
				(type default)
			)
			(layer "F.Fab")
		)
		(fp_line
			(start 0.12065 -0.2794)
			(end 0.12065 -0.3048)
			(stroke
				(width 0.1)
				(type default)
			)
			(layer "F.Fab")
		)
		(fp_line
			(start 0.12065 -0.3048)
			(end 0.67945 -0.3048)
			(stroke
				(width 0.1)
				(type default)
			)
			(layer "F.Fab")
		)
		(fp_line
			(start 0.67945 -0.3048)
			(end 0.67945 0.3048)
			(stroke
				(width 0.1)
				(type default)
			)
			(layer "F.Fab")
		)
		(fp_line
			(start -0.67945 -0.305054)
			(end -0.12065 -0.305054)
			(stroke
				(width 0.1)
				(type default)
			)
			(layer "F.Fab")
		)
		(fp_line
			(start -0.12065 -0.305054)
			(end -0.12065 -0.2794)
			(stroke
				(width 0.1)
				(type default)
			)
			(layer "F.Fab")
		)
		(pad "1" smd circle
			(at -0.40005 0 270)
			(size 0 0)
			(layers "F.Cu" "F.Mask" "F.Paste")
			(net "P1V2_CPU0_USB2_DVDD12")
		)
		(pad "2" smd circle
			(at 0.40005 0 270)
			(size 0 0)
			(layers "F.Cu" "F.Mask" "F.Paste")
			(net "USB_HUB2_TI_PWRCTL2_MRP_VDD12")
		)
	)
	(footprint ""
		(layer "F.Cu")
		(at 294.759888 -392.32205 180)
		(property "Reference" "R1418"
			(at 0 0 180)
			(layer "F.SilkS")
			(hide yes)
			(effects
				(font
					(size 1.27 1.27)
				)
			)
		)
		(property "Value" ""
			(at 0 0 180)
			(layer "F.Fab")
			(effects
				(font
					(size 1.27 1.27)
				)
			)
		)
		(duplicate_pad_numbers_are_jumpers no)
		(fp_line
			(start 0.32512 0.175006)
			(end -0.32512 0.175006)
			(stroke
				(width 0.1)
				(type default)
			)
			(layer "F.Fab")
		)
		(fp_line
			(start 0.32512 -0.175006)
			(end 0.32512 0.175006)
			(stroke
				(width 0.1)
				(type default)
			)
			(layer "F.Fab")
		)
		(fp_line
			(start -0.32512 0.175006)
			(end -0.32512 -0.175006)
			(stroke
				(width 0.1)
				(type default)
			)
			(layer "F.Fab")
		)
		(fp_line
			(start -0.32512 -0.175006)
			(end 0.32512 -0.175006)
			(stroke
				(width 0.1)
				(type default)
			)
			(layer "F.Fab")
		)
		(pad "1" smd rect
			(at -0.2667 0 180)
			(size 0.3048 0.381)
			(layers "F.Cu" "F.Mask" "F.Paste")
			(net "P1V8_CPU0_RT_1D")
		)
		(pad "2" smd rect
			(at 0.2667 0)
			(size 0.3048 0.381)
			(layers "F.Cu" "F.Mask" "F.Paste")
			(net "SMB_RT_CPU0_P1_ROM_MUX_1D_SCL")
		)
	)
	(footprint ""
		(layer "F.Cu")
		(at 328.339958 -194.052952 -90)
		(property "Reference" "R356"
			(at 0 0 270)
			(layer "F.SilkS")
			(hide yes)
			(effects
				(font
					(size 1.27 1.27)
				)
			)
		)
		(property "Value" ""
			(at 0 0 270)
			(layer "F.Fab")
			(effects
				(font
					(size 1.27 1.27)
				)
			)
		)
		(duplicate_pad_numbers_are_jumpers no)
		(fp_line
			(start -0.7874 0.4064)
			(end -0.7874 -0.4064)
			(stroke
				(width 0.1524)
				(type default)
			)
			(layer "F.SilkS")
		)
		(fp_line
			(start 0.7874 0.4064)
			(end -0.7874 0.4064)
			(stroke
				(width 0.1524)
				(type default)
			)
			(layer "F.SilkS")
		)
		(fp_line
			(start -0.7874 -0.4064)
			(end 0.7874 -0.4064)
			(stroke
				(width 0.1524)
				(type default)
			)
			(layer "F.SilkS")
		)
		(fp_line
			(start 0.7874 -0.4064)
			(end 0.7874 0.4064)
			(stroke
				(width 0.1524)
				(type default)
			)
			(layer "F.SilkS")
		)
		(fp_line
			(start -0.67945 0.3048)
			(end -0.67945 -0.305054)
			(stroke
				(width 0.1)
				(type default)
			)
			(layer "F.Fab")
		)
		(fp_line
			(start -0.12065 0.3048)
			(end -0.67945 0.3048)
			(stroke
				(width 0.1)
				(type default)
			)
			(layer "F.Fab")
		)
		(fp_line
			(start 0.120396 0.3048)
			(end 0.120396 0.2794)
			(stroke
				(width 0.1)
				(type default)
			)
			(layer "F.Fab")
		)
		(fp_line
			(start 0.67945 0.3048)
			(end 0.120396 0.3048)
			(stroke
				(width 0.1)
				(type default)
			)
			(layer "F.Fab")
		)
		(fp_line
			(start -0.12065 0.2794)
			(end -0.12065 0.3048)
			(stroke
				(width 0.1)
				(type default)
			)
			(layer "F.Fab")
		)
		(fp_line
			(start 0.120396 0.2794)
			(end -0.12065 0.2794)
			(stroke
				(width 0.1)
				(type default)
			)
			(layer "F.Fab")
		)
		(fp_line
			(start -0.12065 -0.2794)
			(end 0.12065 -0.2794)
			(stroke
				(width 0.1)
				(type default)
			)
			(layer "F.Fab")
		)
		(fp_line
			(start 0.12065 -0.2794)
			(end 0.12065 -0.3048)
			(stroke
				(width 0.1)
				(type default)
			)
			(layer "F.Fab")
		)
		(fp_line
			(start 0.12065 -0.3048)
			(end 0.67945 -0.3048)
			(stroke
				(width 0.1)
				(type default)
			)
			(layer "F.Fab")
		)
		(fp_line
			(start 0.67945 -0.3048)
			(end 0.67945 0.3048)
			(stroke
				(width 0.1)
				(type default)
			)
			(layer "F.Fab")
		)
		(fp_line
			(start -0.67945 -0.305054)
			(end -0.12065 -0.305054)
			(stroke
				(width 0.1)
				(type default)
			)
			(layer "F.Fab")
		)
		(fp_line
			(start -0.12065 -0.305054)
			(end -0.12065 -0.2794)
			(stroke
				(width 0.1)
				(type default)
			)
			(layer "F.Fab")
		)
		(pad "1" smd circle
			(at -0.40005 0 270)
			(size 0 0)
			(layers "F.Cu" "F.Mask" "F.Paste")
			(net "CPU0_XTRIG_R2_L6")
		)
		(pad "2" smd circle
			(at 0.40005 0 270)
			(size 0 0)
			(layers "F.Cu" "F.Mask" "F.Paste")
			(net "CPU0_XTRIG_L6")
		)
	)
	(footprint ""
		(layer "F.Cu")
		(at 320.171318 -115.410488 180)
		(property "Reference" "R43"
			(at 0 0 180)
			(layer "F.SilkS")
			(hide yes)
			(effects
				(font
					(size 1.27 1.27)
				)
			)
		)
		(property "Value" ""
			(at 0 0 180)
			(layer "F.Fab")
			(effects
				(font
					(size 1.27 1.27)
				)
			)
		)
		(duplicate_pad_numbers_are_jumpers no)
		(fp_line
			(start 0.7874 0.4064)
			(end -0.7874 0.4064)
			(stroke
				(width 0.1524)
				(type default)
			)
			(layer "F.SilkS")
		)
		(fp_line
			(start 0.7874 -0.4064)
			(end 0.7874 0.4064)
			(stroke
				(width 0.1524)
				(type default)
			)
			(layer "F.SilkS")
		)
		(fp_line
			(start -0.7874 0.4064)
			(end -0.7874 -0.4064)
			(stroke
				(width 0.1524)
				(type default)
			)
			(layer "F.SilkS")
		)
		(fp_line
			(start -0.7874 -0.4064)
			(end 0.7874 -0.4064)
			(stroke
				(width 0.1524)
				(type default)
			)
			(layer "F.SilkS")
		)
		(fp_line
			(start 0.67945 0.3048)
			(end 0.120396 0.3048)
			(stroke
				(width 0.1)
				(type default)
			)
			(layer "F.Fab")
		)
		(fp_line
			(start 0.67945 -0.3048)
			(end 0.67945 0.3048)
			(stroke
				(width 0.1)
				(type default)
			)
			(layer "F.Fab")
		)
		(fp_line
			(start 0.12065 -0.2794)
			(end 0.12065 -0.3048)
			(stroke
				(width 0.1)
				(type default)
			)
			(layer "F.Fab")
		)
		(fp_line
			(start 0.12065 -0.3048)
			(end 0.67945 -0.3048)
			(stroke
				(width 0.1)
				(type default)
			)
			(layer "F.Fab")
		)
		(fp_line
			(start 0.120396 0.3048)
			(end 0.120396 0.2794)
			(stroke
				(width 0.1)
				(type default)
			)
			(layer "F.Fab")
		)
		(fp_line
			(start 0.120396 0.2794)
			(end -0.12065 0.2794)
			(stroke
				(width 0.1)
				(type default)
			)
			(layer "F.Fab")
		)
		(fp_line
			(start -0.12065 0.3048)
			(end -0.67945 0.3048)
			(stroke
				(width 0.1)
				(type default)
			)
			(layer "F.Fab")
		)
		(fp_line
			(start -0.12065 0.2794)
			(end -0.12065 0.3048)
			(stroke
				(width 0.1)
				(type default)
			)
			(layer "F.Fab")
		)
		(fp_line
			(start -0.12065 -0.2794)
			(end 0.12065 -0.2794)
			(stroke
				(width 0.1)
				(type default)
			)
			(layer "F.Fab")
		)
		(fp_line
			(start -0.12065 -0.305054)
			(end -0.12065 -0.2794)
			(stroke
				(width 0.1)
				(type default)
			)
			(layer "F.Fab")
		)
		(fp_line
			(start -0.67945 0.3048)
			(end -0.67945 -0.305054)
			(stroke
				(width 0.1)
				(type default)
			)
			(layer "F.Fab")
		)
		(fp_line
			(start -0.67945 -0.305054)
			(end -0.12065 -0.305054)
			(stroke
				(width 0.1)
				(type default)
			)
			(layer "F.Fab")
		)
		(pad "1" smd circle
			(at -0.40005 0 180)
			(size 0 0)
			(layers "F.Cu" "F.Mask" "F.Paste")
			(net "P3V3_AUX")
		)
		(pad "2" smd circle
			(at 0.40005 0 180)
			(size 0 0)
			(layers "F.Cu" "F.Mask" "F.Paste")
			(net "SMB_FRU_3V3AUX_R1_SDA")
		)
	)
	(footprint ""
		(layer "F.Cu")
		(at 208.878932 -118.762272)
		(property "Reference" "R3505"
			(at 0 0 0)
			(layer "F.SilkS")
			(hide yes)
			(effects
				(font
					(size 1.27 1.27)
				)
			)
		)
		(property "Value" ""
			(at 0 0 0)
			(layer "F.Fab")
			(effects
				(font
					(size 1.27 1.27)
				)
			)
		)
		(duplicate_pad_numbers_are_jumpers no)
		(fp_line
			(start -0.7874 -0.4064)
			(end 0.7874 -0.4064)
			(stroke
				(width 0.1524)
				(type default)
			)
			(layer "F.SilkS")
		)
		(fp_line
			(start -0.7874 0.4064)
			(end -0.7874 -0.4064)
			(stroke
				(width 0.1524)
				(type default)
			)
			(layer "F.SilkS")
		)
		(fp_line
			(start 0.7874 -0.4064)
			(end 0.7874 0.4064)
			(stroke
				(width 0.1524)
				(type default)
			)
			(layer "F.SilkS")
		)
		(fp_line
			(start 0.7874 0.4064)
			(end -0.7874 0.4064)
			(stroke
				(width 0.1524)
				(type default)
			)
			(layer "F.SilkS")
		)
		(fp_line
			(start -0.67945 -0.305054)
			(end -0.12065 -0.305054)
			(stroke
				(width 0.1)
				(type default)
			)
			(layer "F.Fab")
		)
		(fp_line
			(start -0.67945 0.3048)
			(end -0.67945 -0.305054)
			(stroke
				(width 0.1)
				(type default)
			)
			(layer "F.Fab")
		)
		(fp_line
			(start -0.12065 -0.305054)
			(end -0.12065 -0.2794)
			(stroke
				(width 0.1)
				(type default)
			)
			(layer "F.Fab")
		)
		(fp_line
			(start -0.12065 -0.2794)
			(end 0.12065 -0.2794)
			(stroke
				(width 0.1)
				(type default)
			)
			(layer "F.Fab")
		)
		(fp_line
			(start -0.12065 0.2794)
			(end -0.12065 0.3048)
			(stroke
				(width 0.1)
				(type default)
			)
			(layer "F.Fab")
		)
		(fp_line
			(start -0.12065 0.3048)
			(end -0.67945 0.3048)
			(stroke
				(width 0.1)
				(type default)
			)
			(layer "F.Fab")
		)
		(fp_line
			(start 0.120396 0.2794)
			(end -0.12065 0.2794)
			(stroke
				(width 0.1)
				(type default)
			)
			(layer "F.Fab")
		)
		(fp_line
			(start 0.120396 0.3048)
			(end 0.120396 0.2794)
			(stroke
				(width 0.1)
				(type default)
			)
			(layer "F.Fab")
		)
		(fp_line
			(start 0.12065 -0.3048)
			(end 0.67945 -0.3048)
			(stroke
				(width 0.1)
				(type default)
			)
			(layer "F.Fab")
		)
		(fp_line
			(start 0.12065 -0.2794)
			(end 0.12065 -0.3048)
			(stroke
				(width 0.1)
				(type default)
			)
			(layer "F.Fab")
		)
		(fp_line
			(start 0.67945 -0.3048)
			(end 0.67945 0.3048)
			(stroke
				(width 0.1)
				(type default)
			)
			(layer "F.Fab")
		)
		(fp_line
			(start 0.67945 0.3048)
			(end 0.120396 0.3048)
			(stroke
				(width 0.1)
				(type default)
			)
			(layer "F.Fab")
		)
		(pad "1" smd circle
			(at -0.40005 0)
			(size 0 0)
			(layers "F.Cu" "F.Mask" "F.Paste")
			(net "GPU_FPGA_EROT_FATALERR_ISO_R_N")
		)
		(pad "2" smd circle
			(at 0.40005 0)
			(size 0 0)
			(layers "F.Cu" "F.Mask" "F.Paste")
			(net "GPU_FPGA_EROT_FATALERR_ISO_N")
		)
	)
)
